# TIMECARD (Time Appliance Project (Time Card)) — schematic netlist excerpt (pin names and nets, part order shuffled) for the footprints in the layout excerpt that follows; sources: Cadence DE-HDL packaged netlist, KiCad conversion of R4006-B0001-02_R01.brd

ME8  MEC_NPTH  pkg MTH100C240N  page 34
DS12  OPTICAL  pkg SMC_DS_063X031_V4  page 26 : A = UNNAMED_14_OPTICAL_I289_A ; C = SG

(kicad_pcb
	(version 20260206)
	(generator "pcbnew")
	(generator_version "10.0")
	(general
		(thickness 1.6)
		(legacy_teardrops no)
	)
	(paper "A4")
	(title_block
		(title "timecard-production-celestica-r4006 — R4006-B0001-02_R01.brd")
		(comment 1 "Time Appliance Project (Time Card) / footprints 326-327 of 1113")
	)
	(layers
		(0 "F.Cu" signal "TOP")
		(4 "In1.Cu" signal "L02_GND1")
		(6 "In2.Cu" signal "L03_SIG1")
		(8 "In3.Cu" signal "L04_GND2")
		(10 "In4.Cu" signal "L05_VCC1")
		(12 "In5.Cu" signal "L06_VCC2")
		(14 "In6.Cu" signal "L07_GND3")
		(16 "In7.Cu" signal "L08_SIG2")
		(18 "In8.Cu" signal "L09_GND4")
		(2 "B.Cu" signal "BOTTOM")
		(9 "F.Adhes" user "F.Adhesive")
		(11 "B.Adhes" user "B.Adhesive")
		(13 "F.Paste" user "Package Geometry/Pastemask Top")
		(15 "B.Paste" user "Package Geometry/Pastemask Bottom")
		(5 "F.SilkS" user "Ref Des/Silkscreen Top")
		(7 "B.SilkS" user "Ref Des/Silkscreen Bottom")
		(1 "F.Mask" user "Board Geometry/Soldermask Top")
		(3 "B.Mask" user "Board Geometry/Soldermask Bottom")
		(17 "Dwgs.User" user "User.Drawings")
		(19 "Cmts.User" user "User.Comments")
		(21 "Eco1.User" user "User.Eco1")
		(23 "Eco2.User" user "User.Eco2")
		(25 "Edge.Cuts" user "Board Geometry/Outline")
		(27 "Margin" user)
		(31 "F.CrtYd" user "Package Geometry/Place Bound Top")
		(29 "B.CrtYd" user "Package Geometry/Place Bound Bottom")
		(35 "F.Fab" user "Ref Des/Assembly Top")
		(33 "B.Fab" user "Ref Des/Assembly Bottom")
	)
	(footprint ""
		(layer "F.Cu")
		(at 68.216018 -28.484322)
		(property "Reference" "ME8"
			(at 3.157982 -3.607308 0)
			(unlocked yes)
			(layer "F.SilkS")
			(effects
				(font
					(size 0.7874 0.5842)
					(thickness 0.1524)
				)
			)
		)
		(property "Value" ""
			(at 0 0 0)
			(layer "F.Fab")
			(effects
				(font
					(size 1.27 1.27)
				)
			)
		)
		(duplicate_pad_numbers_are_jumpers no)
		(fp_poly
			(pts
				(arc
					(start 3.556 0)
					(mid -3.556 0)
					(end 3.556 0)
				)
			)
			(stroke
				(width 0)
				(type default)
			)
			(fill no)
			(layer "B.CrtYd")
		)
		(fp_poly
			(pts
				(arc
					(start 3.556 0)
					(mid -3.556 0)
					(end 3.556 0)
				)
			)
			(stroke
				(width 0)
				(type default)
			)
			(fill no)
			(layer "F.CrtYd")
		)
		(fp_circle
			(center 0 0)
			(end 3.048 0)
			(stroke
				(width 0.1)
				(type default)
			)
			(fill no)
			(layer "B.Fab")
		)
		(fp_circle
			(center 0 0)
			(end 3.048 0)
			(stroke
				(width 0.1)
				(type default)
			)
			(fill no)
			(layer "F.Fab")
		)
		(pad "" np_thru_hole circle
			(at 0 0)
			(size 2.286 2.286)
			(drill 2.54)
			(layers "*.Cu" "*.Mask")
			(padstack
				(mode front_inner_back)
				(layer "Inner"
					(shape circle)
					(size 2.286 2.286)
					(clearance 0.4445)
				)
				(layer "B.Cu"
					(shape circle)
					(size 2.286 2.286)
				)
			)
		)
		(zone
			(layers "F.Cu" "B.Cu" "In1.Cu" "In2.Cu" "In3.Cu" "In4.Cu" "In5.Cu" "In6.Cu"
				"In7.Cu" "In8.Cu"
			)
			(hatch none 0.5)
			(connect_pads
				(clearance 0)
			)
			(min_thickness 0.25)
			(keepout
				(tracks not_allowed)
				(vias allowed)
				(pads allowed)
				(copperpour not_allowed)
				(footprints allowed)
			)
			(placement
				(enabled no)
				(sheetname "")
			)
			(fill
				(thermal_gap 0.5)
				(thermal_bridge_width 0.5)
				(island_removal_mode 0)
			)
			(polygon
				(pts
					(arc
						(start 69.790818 -28.484322)
						(mid 66.641218 -28.484322)
						(end 69.790818 -28.484322)
					)
				)
			)
		)
	)
	(footprint ""
		(layer "F.Cu")
		(at 156.04998 -104.350058 -90)
		(property "Reference" "DS12"
			(at 0.591058 -2.23139 90)
			(unlocked yes)
			(layer "F.SilkS")
			(effects
				(font
					(size 0.7874 0.5842)
					(thickness 0.1524)
				)
			)
		)
		(property "Value" ""
			(at 0 0 270)
			(layer "F.Fab")
			(effects
				(font
					(size 1.27 1.27)
				)
			)
		)
		(property "Device Type" "OPTICAL-G170-10143-01"
			(at 0.1778 1.483081 270)
			(unlocked yes)
			(layer "F.Fab")
			(hide yes)
			(effects
				(font
					(size 0.786892 0.583946)
					(thickness 0.000001)
				)
			)
		)
		(property "User Part Number" "PARTNUM*"
			(at 0.1778 2.422881 270)
			(unlocked yes)
			(layer "Cmts.User")
			(hide yes)
			(effects
				(font
					(size 0.786892 0.583946)
					(thickness 0.000001)
				)
			)
		)
		(duplicate_pad_numbers_are_jumpers no)
		(fp_line
			(start -0.9398 1.4732)
			(end -2.2098 1.4732)
			(stroke
				(width 0.1)
				(type default)
			)
			(layer "F.SilkS")
		)
		(fp_line
			(start -1.5748 0.8382)
			(end -1.5748 2.1082)
			(stroke
				(width 0.1)
				(type default)
			)
			(layer "F.SilkS")
		)
		(fp_line
			(start -1.397508 0.704088)
			(end -1.397508 -0.704088)
			(stroke
				(width 0.1)
				(type default)
			)
			(layer "F.SilkS")
		)
		(fp_line
			(start 1.397508 0.704088)
			(end -1.397508 0.704088)
			(stroke
				(width 0.1)
				(type default)
			)
			(layer "F.SilkS")
		)
		(fp_line
			(start -1.397508 -0.704088)
			(end 1.397508 -0.704088)
			(stroke
				(width 0.1)
				(type default)
			)
			(layer "F.SilkS")
		)
		(fp_line
			(start 1.397508 -0.704088)
			(end 1.397508 0.704088)
			(stroke
				(width 0.1)
				(type default)
			)
			(layer "F.SilkS")
		)
		(fp_poly
			(pts
				(xy 1.397508 0.704088) (xy 1.397508 -0.704088) (xy 1.905508 -0.704088) (xy 1.905508 0.704088)
			)
			(stroke
				(width 0)
				(type default)
			)
			(fill yes)
			(layer "F.SilkS")
		)
		(fp_poly
			(pts
				(xy -1.651508 0.958088) (xy 1.905508 0.958088) (xy 1.905508 -0.958088) (xy -1.651508 -0.958088)
			)
			(stroke
				(width 0)
				(type default)
			)
			(fill no)
			(layer "F.CrtYd")
		)
		(fp_line
			(start -0.9398 1.3462)
			(end -2.2098 1.3462)
			(stroke
				(width 0.1)
				(type default)
			)
			(layer "F.Fab")
		)
		(fp_line
			(start -1.5748 0.7112)
			(end -1.5748 1.9812)
			(stroke
				(width 0.1)
				(type default)
			)
			(layer "F.Fab")
		)
		(fp_line
			(start -0.850138 0.450088)
			(end 0.850138 0.450088)
			(stroke
				(width 0.1)
				(type default)
			)
			(layer "F.Fab")
		)
		(fp_line
			(start 0.850138 0.450088)
			(end 0.850138 -0.450088)
			(stroke
				(width 0.1)
				(type default)
			)
			(layer "F.Fab")
		)
		(fp_line
			(start -0.850138 -0.450088)
			(end -0.850138 0.450088)
			(stroke
				(width 0.1)
				(type default)
			)
			(layer "F.Fab")
		)
		(fp_line
			(start 0.850138 -0.450088)
			(end -0.850138 -0.450088)
			(stroke
				(width 0.1)
				(type default)
			)
			(layer "F.Fab")
		)
		(fp_poly
			(pts
				(xy 0.850138 -0.450088) (xy 0.850138 0.450088) (xy 0.342138 0.450088) (xy 0.342138 -0.450088)
			)
			(stroke
				(width 0)
				(type default)
			)
			(fill yes)
			(layer "F.Fab")
		)
		(fp_text user "C"
			(at 2.400808 -1.04902 0)
			(unlocked yes)
			(layer "F.SilkS")
			(effects
				(font
					(size 0.635 0.4064)
					(thickness 0.1524)
				)
			)
		)
		(fp_text user "A"
			(at -0.901192 -1.17602 0)
			(unlocked yes)
			(layer "F.SilkS")
			(effects
				(font
					(size 0.635 0.4064)
					(thickness 0.1524)
				)
			)
		)
		(fp_text user "A"
			(at -0.893572 0.85598 0)
			(unlocked yes)
			(layer "F.Fab")
			(effects
				(font
					(size 0.7874 0.5842)
					(thickness 0.1524)
				)
			)
		)
		(fp_text user "C"
			(at 1.900428 -1.30302 0)
			(unlocked yes)
			(layer "F.Fab")
			(effects
				(font
					(size 0.7874 0.5842)
					(thickness 0.1524)
				)
			)
		)
		(pad "A" smd rect
			(at -0.749808 0 270)
			(size 0.7874 0.7874)
			(layers "F.Cu" "F.Mask" "F.Paste")
			(net "UNNAMED_14_OPTICAL_I289_A")
		)
		(pad "C" smd rect
			(at 0.749808 0 270)
			(size 0.7874 0.7874)
			(layers "F.Cu" "F.Mask" "F.Paste")
			(net "SG")
		)
	)
)
